(kicad_pcb
	(version 20211014)
	(generator pcbnew)
	(general
    (thickness 1.6)
  )
	(paper "A4")
	(title_block
    (title "SA800U (Snapdragon 845) Baseboard")
    (date "2023-10-19")
    (rev "1.0.3")
    (company "Antmicro Ltd.")
    (comment 1 "www.antmicro.com")
		(comment 9 "footprints 216-224 of 589")
	)
	(layers
    (0 "F.Cu" signal)
    (1 "In1.Cu" power)
    (2 "In2.Cu" signal)
    (3 "In3.Cu" signal)
    (4 "In4.Cu" power)
    (31 "B.Cu" signal)
    (32 "B.Adhes" user "B.Adhesive")
    (33 "F.Adhes" user "F.Adhesive")
    (34 "B.Paste" user)
    (35 "F.Paste" user)
    (36 "B.SilkS" user "B.Silkscreen")
    (37 "F.SilkS" user "F.Silkscreen")
    (38 "B.Mask" user)
    (39 "F.Mask" user)
    (40 "Dwgs.User" user "User.Drawings")
    (41 "Cmts.User" user "User.Comments")
    (42 "Eco1.User" user "User.Eco1")
    (43 "Eco2.User" user "User.Eco2")
    (44 "Edge.Cuts" user)
    (45 "Margin" user)
    (46 "B.CrtYd" user "B.Courtyard")
    (47 "F.CrtYd" user "F.Courtyard")
    (48 "B.Fab" user)
    (49 "F.Fab" user)
  )
	(footprint "sa800u-baseboard-hw-footprints:L_Murata_025020_0605Metric" (layer "F.Cu")
    (tedit 61AA2C4F)
    (at 143.65 136.85 -90)
    (property "Author" "Antmicro")
    (property "License" "Apache-2.0")
    (property "MPN" "NFP0QHB242HS2D")
    (property "Manufacturer" "Murata")
    (property "Sheetfile" "hdmi-converter.kicad_sch")
    (property "Sheetname" "HDMI converter")
    (attr smd)
    (fp_text reference "L8" (at -4.55 16.16 -90) (layer "F.SilkS")
      (effects (font (size 0.7 0.7) (thickness 0.15)) (justify left bottom))
    )
    (fp_text value "NFP0QHB242HS2D" (at 0 1.55 -90) (layer "F.Fab")
      (effects (font (size 0.7 0.7) (thickness 0.15)) (justify left bottom))
    )
    (fp_text user "License: Apache-2.0" (at -1.027 5.805 -90) (layer "F.Fab") hide
      (effects (font (size 0.7 0.7) (thickness 0.15)) (justify left bottom))
    )
    (fp_text user "Author: Antmicro" (at -1.027 4.605 -90) (layer "F.Fab") hide
      (effects (font (size 0.7 0.7) (thickness 0.15)) (justify left bottom))
    )
    (fp_text user "${REFERENCE}" (at -1.027 3.406 -90) (layer "F.Fab") hide
      (effects (font (size 0.7 0.7) (thickness 0.15)) (justify left bottom))
    )
    (fp_line (start -0.276 0.45) (end 0.276 0.45) (layer "F.SilkS") (width 0.15))
    (fp_line (start 0.276 -0.45) (end -0.276 -0.45) (layer "F.SilkS") (width 0.15))
    (fp_circle (center -0.5 -0.5) (end -0.449 -0.5) (layer "F.SilkS") (width 0.15) (fill solid))
    (fp_rect (start -0.5 -0.6) (end 0.5 0.6) (layer "F.CrtYd") (width 0.05) (fill none))
    (fp_line (start -0.277 -0.351) (end -0.277 0.349) (layer "F.Fab") (width 0.15))
    (fp_line (start 0.275 -0.351) (end -0.277 -0.351) (layer "F.Fab") (width 0.15))
    (fp_line (start -0.277 0.349) (end 0.275 0.349) (layer "F.Fab") (width 0.15))
    (fp_line (start 0.275 0.349) (end 0.275 -0.351) (layer "F.Fab") (width 0.15))
    (pad "1" smd rect (at -0.25 -0.24 270) (size 0.3 0.23) (layers "F.Cu" "F.Paste" "F.Mask")
      (net 198 "/HDMI converter/HDMI_TX1_P") (pinfunction "1") (pintype "passive"))
    (pad "2" smd rect (at 0.248 -0.24 270) (size 0.3 0.23) (layers "F.Cu" "F.Paste" "F.Mask")
      (net 241 "/HDMI converter/HDMI_TX1_CONN_P") (pinfunction "2") (pintype "passive"))
    (pad "3" smd rect (at 0.248 0.239 270) (size 0.3 0.23) (layers "F.Cu" "F.Paste" "F.Mask")
      (net 242 "/HDMI converter/HDMI_TX1_CONN_N") (pinfunction "3") (pintype "passive"))
    (pad "4" smd rect (at -0.25 0.239 270) (size 0.3 0.23) (layers "F.Cu" "F.Paste" "F.Mask")
      (net 200 "/HDMI converter/HDMI_TX1_N") (pinfunction "4") (pintype "passive"))
  )
	(footprint "sa800u-baseboard-hw-footprints:L_Murata_025020_0605Metric" (layer "F.Cu")
    (tedit 61AA2C4F)
    (at 146.85 136.85 -90)
    (property "Author" "Antmicro")
    (property "License" "Apache-2.0")
    (property "MPN" "NFP0QHB242HS2D")
    (property "Manufacturer" "Murata")
    (property "Sheetfile" "hdmi-converter.kicad_sch")
    (property "Sheetname" "HDMI converter")
    (attr smd)
    (fp_text reference "L7" (at -4.57 16.65 -90) (layer "F.SilkS")
      (effects (font (size 0.7 0.7) (thickness 0.15)) (justify left bottom))
    )
    (fp_text value "NFP0QHB242HS2D" (at 0 1.55 -90) (layer "F.Fab")
      (effects (font (size 0.7 0.7) (thickness 0.15)) (justify left bottom))
    )
    (fp_text user "License: Apache-2.0" (at -1.027 5.805 -90) (layer "F.Fab") hide
      (effects (font (size 0.7 0.7) (thickness 0.15)) (justify left bottom))
    )
    (fp_text user "Author: Antmicro" (at -1.027 4.605 -90) (layer "F.Fab") hide
      (effects (font (size 0.7 0.7) (thickness 0.15)) (justify left bottom))
    )
    (fp_text user "${REFERENCE}" (at -1.027 3.406 -90) (layer "F.Fab") hide
      (effects (font (size 0.7 0.7) (thickness 0.15)) (justify left bottom))
    )
    (fp_line (start 0.276 -0.45) (end -0.276 -0.45) (layer "F.SilkS") (width 0.15))
    (fp_line (start -0.276 0.45) (end 0.276 0.45) (layer "F.SilkS") (width 0.15))
    (fp_circle (center -0.5 -0.5) (end -0.449 -0.5) (layer "F.SilkS") (width 0.15) (fill solid))
    (fp_rect (start -0.5 -0.6) (end 0.5 0.6) (layer "F.CrtYd") (width 0.05) (fill none))
    (fp_line (start -0.277 -0.351) (end -0.277 0.349) (layer "F.Fab") (width 0.15))
    (fp_line (start 0.275 0.349) (end 0.275 -0.351) (layer "F.Fab") (width 0.15))
    (fp_line (start -0.277 0.349) (end 0.275 0.349) (layer "F.Fab") (width 0.15))
    (fp_line (start 0.275 -0.351) (end -0.277 -0.351) (layer "F.Fab") (width 0.15))
    (pad "1" smd rect (at -0.25 -0.24 270) (size 0.3 0.23) (layers "F.Cu" "F.Paste" "F.Mask")
      (net 193 "/HDMI converter/HDMI_TX2_P") (pinfunction "1") (pintype "passive"))
    (pad "2" smd rect (at 0.248 -0.24 270) (size 0.3 0.23) (layers "F.Cu" "F.Paste" "F.Mask")
      (net 243 "/HDMI converter/HDMI_TX2_CONN_P") (pinfunction "2") (pintype "passive"))
    (pad "3" smd rect (at 0.248 0.239 270) (size 0.3 0.23) (layers "F.Cu" "F.Paste" "F.Mask")
      (net 240 "/HDMI converter/HDMI_TX2_CONN_N") (pinfunction "3") (pintype "passive"))
    (pad "4" smd rect (at -0.25 0.239 270) (size 0.3 0.23) (layers "F.Cu" "F.Paste" "F.Mask")
      (net 195 "/HDMI converter/HDMI_TX2_N") (pinfunction "4") (pintype "passive"))
  )
	(footprint "sa800u-baseboard-hw-footprints:R_0402_1005Metric" (layer "F.Cu")
    (tedit 5FD9C158)
    (at 142.7 133.05 -90)
    (descr "Resistor SMD 0402")
    (tags "resistor SMD 0402")
    (property "Author" "Antmicro")
    (property "License" "Apache-2.0")
    (property "MPN" "CR0402-FX-50R0GLF")
    (property "Manufacturer" "Bourns")
    (property "Sheetfile" "hdmi-converter.kicad_sch")
    (property "Sheetname" "HDMI converter")
    (property "Tolerance" "1%")
    (property "Val" "50R")
    (attr smd)
    (fp_text reference "R40" (at -4.66 15.99 -90) (layer "F.SilkS")
      (effects (font (size 0.7 0.7) (thickness 0.15)) (justify left bottom))
    )
    (fp_text value "R_50R_0402" (at 0 1.4 -90) (layer "F.Fab")
      (effects (font (size 0.7 0.7) (thickness 0.15)) (justify left bottom))
    )
    (fp_text user "License: Apache-2.0" (at -0.95 5.169 -90) (layer "F.Fab") hide
      (effects (font (size 0.7 0.7) (thickness 0.15)) (justify left bottom))
    )
    (fp_text user "${REFERENCE}" (at -0.95 3.168 -90) (layer "F.Fab") hide
      (effects (font (size 0.7 0.7) (thickness 0.15)) (justify left bottom))
    )
    (fp_text user "Author: Antmicro" (at -0.95 4.169 -90) (layer "F.Fab") hide
      (effects (font (size 0.7 0.7) (thickness 0.15)) (justify left bottom))
    )
    (fp_rect (start -0.93 -0.47) (end 0.93 0.47) (layer "F.CrtYd") (width 0.05) (fill none))
    (fp_rect (start -0.5 -0.25) (end 0.5 0.25) (layer "F.Fab") (width 0.15) (fill none))
    (pad "1" smd roundrect (at -0.485 0 270) (size 0.59 0.64) (layers "F.Cu" "F.Paste" "F.Mask") (roundrect_rratio 0.25)
      (net 187 "/HDMI converter/LT9611_VCC33_TX") (pintype "passive"))
    (pad "2" smd roundrect (at 0.485 0 270) (size 0.59 0.64) (layers "F.Cu" "F.Paste" "F.Mask") (roundrect_rratio 0.25)
      (net 199 "/HDMI converter/HDMI_TX_D1_N") (pintype "passive"))
  )
	(footprint "sa800u-baseboard-hw-footprints:R_0402_1005Metric" (layer "F.Cu")
    (tedit 5FD9C158)
    (at 145.9 133.05 -90)
    (descr "Resistor SMD 0402")
    (tags "resistor SMD 0402")
    (property "Author" "Antmicro")
    (property "License" "Apache-2.0")
    (property "MPN" "CR0402-FX-50R0GLF")
    (property "Manufacturer" "Bourns")
    (property "Sheetfile" "hdmi-converter.kicad_sch")
    (property "Sheetname" "HDMI converter")
    (property "Tolerance" "1%")
    (property "Val" "50R")
    (attr smd)
    (fp_text reference "R45" (at -4.601 16.48 -90) (layer "F.SilkS")
      (effects (font (size 0.7 0.7) (thickness 0.15)) (justify left bottom))
    )
    (fp_text value "R_50R_0402" (at 0 1.4 -90) (layer "F.Fab")
      (effects (font (size 0.7 0.7) (thickness 0.15)) (justify left bottom))
    )
    (fp_text user "Author: Antmicro" (at -0.95 4.169 -90) (layer "F.Fab") hide
      (effects (font (size 0.7 0.7) (thickness 0.15)) (justify left bottom))
    )
    (fp_text user "${REFERENCE}" (at -0.95 3.168 -90) (layer "F.Fab") hide
      (effects (font (size 0.7 0.7) (thickness 0.15)) (justify left bottom))
    )
    (fp_text user "License: Apache-2.0" (at -0.95 5.169 -90) (layer "F.Fab") hide
      (effects (font (size 0.7 0.7) (thickness 0.15)) (justify left bottom))
    )
    (fp_rect (start -0.93 -0.47) (end 0.93 0.47) (layer "F.CrtYd") (width 0.05) (fill none))
    (fp_rect (start -0.5 -0.25) (end 0.5 0.25) (layer "F.Fab") (width 0.15) (fill none))
    (pad "1" smd roundrect (at -0.485 0 270) (size 0.59 0.64) (layers "F.Cu" "F.Paste" "F.Mask") (roundrect_rratio 0.25)
      (net 187 "/HDMI converter/LT9611_VCC33_TX") (pintype "passive"))
    (pad "2" smd roundrect (at 0.485 0 270) (size 0.59 0.64) (layers "F.Cu" "F.Paste" "F.Mask") (roundrect_rratio 0.25)
      (net 196 "/HDMI converter/HDMI_TX_D2_N") (pintype "passive"))
  )
	(footprint "sa800u-baseboard-hw-footprints:C_0402_1005Metric" (layer "F.Cu")
    (tedit 616D63CF)
    (at 146.35 134.95 -90)
    (descr "Capacitor SMD 0402")
    (tags "capacitor SMD 0402")
    (property "Author" "Antmicro")
    (property "Dielectric" "X5R")
    (property "License" "Apache-2.0")
    (property "MPN" "GRM155R61H104KE14D")
    (property "Manufacturer" "Murata")
    (property "Sheetfile" "hdmi-converter.kicad_sch")
    (property "Sheetname" "HDMI converter")
    (property "Val" "100n")
    (property "Voltage" "50V")
    (attr smd)
    (fp_text reference "C46" (at -4.6 16.48 -90) (layer "F.SilkS")
      (effects (font (size 0.7 0.7) (thickness 0.15)) (justify left bottom))
    )
    (fp_text value "C_100n_0402" (at 0 1.4 -90) (layer "F.Fab")
      (effects (font (size 0.7 0.7) (thickness 0.15)) (justify left bottom))
    )
    (fp_text user "${REFERENCE}" (at -0.932 3.168 -90) (layer "F.Fab") hide
      (effects (font (size 0.7 0.7) (thickness 0.15)) (justify left bottom))
    )
    (fp_text user "Author: Antmicro" (at -0.932 4.17 -90) (layer "F.Fab") hide
      (effects (font (size 0.7 0.7) (thickness 0.15)) (justify left bottom))
    )
    (fp_text user "License: Apache-2.0" (at -0.932 5.17 -90) (layer "F.Fab") hide
      (effects (font (size 0.7 0.7) (thickness 0.15)) (justify left bottom))
    )
    (fp_rect (start -0.94 -0.47) (end 0.94 0.47) (layer "F.CrtYd") (width 0.05) (fill none))
    (fp_rect (start -0.499 -0.249) (end 0.499 0.249) (layer "F.Fab") (width 0.15) (fill none))
    (pad "1" smd roundrect (at -0.484 0 270) (size 0.59 0.64) (layers "F.Cu" "F.Paste" "F.Mask") (roundrect_rratio 0.25)
      (net 196 "/HDMI converter/HDMI_TX_D2_N") (pintype "passive"))
    (pad "2" smd roundrect (at 0.484 0 270) (size 0.59 0.64) (layers "F.Cu" "F.Paste" "F.Mask") (roundrect_rratio 0.25)
      (net 195 "/HDMI converter/HDMI_TX2_N") (pintype "passive"))
  )
	(footprint "sa800u-baseboard-hw-footprints:C_0402_1005Metric" (layer "F.Cu")
    (tedit 616D63CF)
    (at 135.238164 129.09 180)
    (descr "Capacitor SMD 0402")
    (tags "capacitor SMD 0402")
    (property "Author" "Antmicro")
    (property "Dielectric" "X5R")
    (property "License" "Apache-2.0")
    (property "MPN" "GRM155R61H104KE14D")
    (property "Manufacturer" "Murata")
    (property "Sheetfile" "hdmi-converter.kicad_sch")
    (property "Sheetname" "HDMI converter")
    (property "Val" "100n")
    (property "Voltage" "50V")
    (attr smd)
    (fp_text reference "C37" (at 3.028164 -0.477047 180) (layer "F.SilkS")
      (effects (font (size 0.7 0.7) (thickness 0.15)) (justify left bottom))
    )
    (fp_text value "C_100n_0402" (at 0 1.4 180) (layer "F.Fab")
      (effects (font (size 0.7 0.7) (thickness 0.15)) (justify left bottom))
    )
    (fp_text user "Author: Antmicro" (at -0.932 4.17 180) (layer "F.Fab") hide
      (effects (font (size 0.7 0.7) (thickness 0.15)) (justify left bottom))
    )
    (fp_text user "License: Apache-2.0" (at -0.932 5.17 180) (layer "F.Fab") hide
      (effects (font (size 0.7 0.7) (thickness 0.15)) (justify left bottom))
    )
    (fp_text user "${REFERENCE}" (at -0.932 3.168 180) (layer "F.Fab") hide
      (effects (font (size 0.7 0.7) (thickness 0.15)) (justify left bottom))
    )
    (fp_rect (start -0.94 -0.47) (end 0.94 0.47) (layer "F.CrtYd") (width 0.05) (fill none))
    (fp_rect (start -0.499 -0.249) (end 0.499 0.249) (layer "F.Fab") (width 0.15) (fill none))
    (pad "1" smd roundrect (at -0.484 0 180) (size 0.59 0.64) (layers "F.Cu" "F.Paste" "F.Mask") (roundrect_rratio 0.25)
      (net 188 "/HDMI converter/LT9611_VDD12") (pintype "passive"))
    (pad "2" smd roundrect (at 0.484 0 180) (size 0.59 0.64) (layers "F.Cu" "F.Paste" "F.Mask") (roundrect_rratio 0.25)
      (net 1 "GND") (pintype "passive"))
  )
	(footprint "sa800u-baseboard-hw-footprints:C_0402_1005Metric" (layer "F.Cu")
    (tedit 616D63CF)
    (at 136.15 138.8 -90)
    (descr "Capacitor SMD 0402")
    (tags "capacitor SMD 0402")
    (property "Author" "Antmicro")
    (property "Dielectric" "X5R")
    (property "License" "Apache-2.0")
    (property "MPN" "GRM155R61H104KE14D")
    (property "Manufacturer" "Murata")
    (property "Sheetfile" "hdmi-converter.kicad_sch")
    (property "Sheetname" "HDMI converter")
    (property "Val" "100n")
    (property "Voltage" "50V")
    (attr smd)
    (fp_text reference "C55" (at 3.09 -0.38 -90) (layer "F.SilkS")
      (effects (font (size 0.7 0.7) (thickness 0.15)) (justify left bottom))
    )
    (fp_text value "C_100n_0402" (at 0 1.4 -90) (layer "F.Fab")
      (effects (font (size 0.7 0.7) (thickness 0.15)) (justify left bottom))
    )
    (fp_text user "Author: Antmicro" (at -0.932 4.17 -90) (layer "F.Fab") hide
      (effects (font (size 0.7 0.7) (thickness 0.15)) (justify left bottom))
    )
    (fp_text user "License: Apache-2.0" (at -0.932 5.17 -90) (layer "F.Fab") hide
      (effects (font (size 0.7 0.7) (thickness 0.15)) (justify left bottom))
    )
    (fp_text user "${REFERENCE}" (at -0.932 3.168 -90) (layer "F.Fab") hide
      (effects (font (size 0.7 0.7) (thickness 0.15)) (justify left bottom))
    )
    (fp_rect (start -0.94 -0.47) (end 0.94 0.47) (layer "F.CrtYd") (width 0.05) (fill none))
    (fp_rect (start -0.499 -0.249) (end 0.499 0.249) (layer "F.Fab") (width 0.15) (fill none))
    (pad "1" smd roundrect (at -0.484 0 270) (size 0.59 0.64) (layers "F.Cu" "F.Paste" "F.Mask") (roundrect_rratio 0.25)
      (net 209 "/HDMI converter/VCOM") (pintype "passive"))
    (pad "2" smd roundrect (at 0.484 0 270) (size 0.59 0.64) (layers "F.Cu" "F.Paste" "F.Mask") (roundrect_rratio 0.25)
      (net 1 "GND") (pintype "passive"))
  )
	(footprint "sa800u-baseboard-hw-footprints:R_0402_1005Metric" (layer "F.Cu")
    (tedit 5FD9C158)
    (at 147.8 133.05 -90)
    (descr "Resistor SMD 0402")
    (tags "resistor SMD 0402")
    (property "Author" "Antmicro")
    (property "License" "Apache-2.0")
    (property "MPN" "CR0402-FX-50R0GLF")
    (property "Manufacturer" "Bourns")
    (property "Sheetfile" "hdmi-converter.kicad_sch")
    (property "Sheetname" "HDMI converter")
    (property "Tolerance" "1%")
    (property "Val" "50R")
    (attr smd)
    (fp_text reference "R47" (at -4.66 16.68 -90) (layer "F.SilkS")
      (effects (font (size 0.7 0.7) (thickness 0.15)) (justify left bottom))
    )
    (fp_text value "R_50R_0402" (at 0 1.4 -90) (layer "F.Fab")
      (effects (font (size 0.7 0.7) (thickness 0.15)) (justify left bottom))
    )
    (fp_text user "License: Apache-2.0" (at -0.95 5.169 -90) (layer "F.Fab") hide
      (effects (font (size 0.7 0.7) (thickness 0.15)) (justify left bottom))
    )
    (fp_text user "${REFERENCE}" (at -0.95 3.168 -90) (layer "F.Fab") hide
      (effects (font (size 0.7 0.7) (thickness 0.15)) (justify left bottom))
    )
    (fp_text user "Author: Antmicro" (at -0.95 4.169 -90) (layer "F.Fab") hide
      (effects (font (size 0.7 0.7) (thickness 0.15)) (justify left bottom))
    )
    (fp_rect (start -0.93 -0.47) (end 0.93 0.47) (layer "F.CrtYd") (width 0.05) (fill none))
    (fp_rect (start -0.5 -0.25) (end 0.5 0.25) (layer "F.Fab") (width 0.15) (fill none))
    (pad "1" smd roundrect (at -0.485 0 270) (size 0.59 0.64) (layers "F.Cu" "F.Paste" "F.Mask") (roundrect_rratio 0.25)
      (net 187 "/HDMI converter/LT9611_VCC33_TX") (pintype "passive"))
    (pad "2" smd roundrect (at 0.485 0 270) (size 0.59 0.64) (layers "F.Cu" "F.Paste" "F.Mask") (roundrect_rratio 0.25)
      (net 194 "/HDMI converter/HDMI_TX_D2_P") (pintype "passive"))
  )
	(footprint "sa800u-baseboard-hw-footprints:LED_0603_1608Metric_G" (layer "F.Cu")
    (tedit 60C2DD7B)
    (at 68.7 118.6 90)
    (descr "LED SMD 0603 Green")
    (tags "LED SMD 0603 Green")
    (property "Author" "Antmicro")
    (property "License" "Apache-2.0")
    (property "MPN" "KP-1608ZGC")
    (property "Manufacturer" "Kingbright")
    (property "Sheetfile" "poe.kicad_sch")
    (property "Sheetname" "PoE")
    (attr smd)
    (fp_text reference "D32" (at -1.62 -0.78 90) (layer "F.SilkS")
      (effects (font (size 0.7 0.7) (thickness 0.15)) (justify left bottom))
    )
    (fp_text value "KP-1608EC" (at 0 1.6 90) (layer "F.Fab")
      (effects (font (size 0.7 0.7) (thickness 0.15)) (justify left bottom))
    )
    (fp_text user "License: Apache-2.0" (at -1.31 5.769 90) (layer "F.Fab") hide
      (effects (font (size 0.7 0.7) (thickness 0.15)) (justify left bottom))
    )
    (fp_text user "Author: Antmicro" (at -1.31 4.769 90) (layer "F.Fab") hide
      (effects (font (size 0.7 0.7) (thickness 0.15)) (justify left bottom))
    )
    (fp_text user "${REFERENCE}" (at -1.31 3.769 90) (layer "F.Fab") hide
      (effects (font (size 0.7 0.7) (thickness 0.15)) (justify left bottom))
    )
    (fp_line (start -0.27 -0.35) (end 0.27 -0.35) (layer "F.SilkS") (width 0.15))
    (fp_line (start -0.106328 -0.200008) (end -0.106328 0.199992) (layer "F.SilkS") (width 0.1))
    (fp_line (start 0.093672 -0.200008) (end 0.093672 0.199992) (layer "F.SilkS") (width 0.1))
    (fp_line (start 1.25 0.32) (end 1.25 -0.32) (layer "F.SilkS") (width 0.15))
    (fp_line (start -0.106328 -0.000008) (end -0.29 0) (layer "F.SilkS") (width 0.1))
    (fp_line (start -0.27 0.351) (end 0.27 0.351) (layer "F.SilkS") (width 0.15))
    (fp_line (start -0.106328 -0.200008) (end 0.093672 -0.000008) (layer "F.SilkS") (width 0.1))
    (fp_line (start 0.093672 -0.000008) (end 0.293672 -0.000008) (layer "F.SilkS") (width 0.1))
    (fp_line (start 0.093672 -0.000008) (end -0.106328 0.199992) (layer "F.SilkS") (width 0.1))
    (fp_rect (start 1.26 0.65) (end -1.26 -0.65) (layer "F.CrtYd") (width 0.05) (fill none))
    (fp_line (start -0.201 0) (end -0.201 0.202) (layer "F.Fab") (width 0.15))
    (fp_line (start 0.199 0) (end 0.597 0) (layer "F.Fab") (width 0.15))
    (fp_line (start 0.199 0.202) (end 0.199 -0.1) (layer "F.Fab") (width 0.15))
    (fp_line (start -0.201 -0.2) (end -0.201 0) (layer "F.Fab") (width 0.15))
    (fp_line (start -0.201 0.202) (end 0.101 0) (layer "F.Fab") (width 0.15))
    (fp_line (start -0.599 0) (end -0.201 0) (layer "F.Fab") (width 0.15))
    (fp_line (start 0.101 0) (end -0.201 -0.2) (layer "F.Fab") (width 0.15))
    (fp_line (start 0.199 -0.2) (end 0.199 -0.1) (layer "F.Fab") (width 0.15))
    (fp_rect (start -0.848 -0.4) (end 0.85 0.402) (layer "F.Fab") (width 0.15) (fill none))
    (pad "1" smd rect (at -0.75 0 270) (size 0.8 0.8) (layers "F.Cu" "F.Paste" "F.Mask")
      (net 380 "Net-(D32-Pad1)") (pinfunction "1") (pintype "passive"))
    (pad "2" smd rect (at 0.75 0 270) (size 0.8 0.8) (layers "F.Cu" "F.Paste" "F.Mask")
      (net 7 "GNDD") (pinfunction "2") (pintype "passive"))
  )
)
